(kicad_pcb
	(version 20260206)
	(generator "pcbnew")
	(generator_version "10.0")
	(general
		(thickness 1.6)
		(legacy_teardrops no)
	)
	(paper "A4")
	(title_block
		(title "01162023_DA0F0TEBIF0_F0T_Expander_BD_F_brd_V02_OCP.brd")
		(comment 1 "Grand Teton / footprints 2275-2281 of 9728")
	)
	(layers
		(0 "F.Cu" signal "TOP")
		(4 "In1.Cu" signal "GND")
		(6 "In2.Cu" signal "VCC")
		(8 "In3.Cu" signal "VCC1")
		(10 "In4.Cu" signal "GND1")
		(12 "In5.Cu" signal "IN1")
		(14 "In6.Cu" signal "GND2")
		(16 "In7.Cu" signal "IN2")
		(18 "In8.Cu" signal "GND3")
		(20 "In9.Cu" signal "IN3")
		(22 "In10.Cu" signal "GND4")
		(24 "In11.Cu" signal "IN4")
		(26 "In12.Cu" signal "GND5")
		(28 "In13.Cu" signal "IN5")
		(30 "In14.Cu" signal "GND6")
		(32 "In15.Cu" signal "IN6")
		(34 "In16.Cu" signal "GND7")
		(2 "B.Cu" signal "BOTTOM")
		(9 "F.Adhes" user "F.Adhesive")
		(11 "B.Adhes" user "B.Adhesive")
		(13 "F.Paste" user "Package Geometry/Pastemask Top")
		(15 "B.Paste" user "Package Geometry/Pastemask Bottom")
		(5 "F.SilkS" user "Ref Des/Silkscreen Top")
		(7 "B.SilkS" user "Ref Des/Silkscreen Bottom")
		(1 "F.Mask" user "Board Geometry/Soldermask Top")
		(3 "B.Mask" user "Board Geometry/Soldermask Bottom")
		(17 "Dwgs.User" user "User.Drawings")
		(19 "Cmts.User" user "User.Comments")
		(21 "Eco1.User" user "User.Eco1")
		(23 "Eco2.User" user "User.Eco2")
		(25 "Edge.Cuts" user "Board Geometry/Outline")
		(27 "Margin" user)
		(31 "F.CrtYd" user "Package Geometry/Place Bound Top")
		(29 "B.CrtYd" user "Package Geometry/Place Bound Bottom")
		(35 "F.Fab" user "Ref Des/Assembly Top")
		(33 "B.Fab" user "Ref Des/Assembly Bottom")
	)
	(footprint ""
		(layer "F.Cu")
		(at 224.022158 -85.684868 180)
		(property "Reference" "R4260"
			(at 0 0 180)
			(layer "F.SilkS")
			(hide yes)
			(effects
				(font
					(size 1.27 1.27)
				)
			)
		)
		(property "Value" ""
			(at 0 0 180)
			(layer "F.Fab")
			(effects
				(font
					(size 1.27 1.27)
				)
			)
		)
		(duplicate_pad_numbers_are_jumpers no)
		(fp_line
			(start 0.7874 0.4064)
			(end -0.7874 0.4064)
			(stroke
				(width 0.1524)
				(type default)
			)
			(layer "F.SilkS")
		)
		(fp_line
			(start 0.7874 -0.4064)
			(end 0.7874 0.4064)
			(stroke
				(width 0.1524)
				(type default)
			)
			(layer "F.SilkS")
		)
		(fp_line
			(start -0.7874 0.4064)
			(end -0.7874 -0.4064)
			(stroke
				(width 0.1524)
				(type default)
			)
			(layer "F.SilkS")
		)
		(fp_line
			(start -0.7874 -0.4064)
			(end 0.7874 -0.4064)
			(stroke
				(width 0.1524)
				(type default)
			)
			(layer "F.SilkS")
		)
		(fp_line
			(start 0.67945 0.3048)
			(end 0.120396 0.3048)
			(stroke
				(width 0.1)
				(type default)
			)
			(layer "F.Fab")
		)
		(fp_line
			(start 0.67945 -0.3048)
			(end 0.67945 0.3048)
			(stroke
				(width 0.1)
				(type default)
			)
			(layer "F.Fab")
		)
		(fp_line
			(start 0.12065 -0.2794)
			(end 0.12065 -0.3048)
			(stroke
				(width 0.1)
				(type default)
			)
			(layer "F.Fab")
		)
		(fp_line
			(start 0.12065 -0.3048)
			(end 0.67945 -0.3048)
			(stroke
				(width 0.1)
				(type default)
			)
			(layer "F.Fab")
		)
		(fp_line
			(start 0.120396 0.3048)
			(end 0.120396 0.2794)
			(stroke
				(width 0.1)
				(type default)
			)
			(layer "F.Fab")
		)
		(fp_line
			(start 0.120396 0.2794)
			(end -0.12065 0.2794)
			(stroke
				(width 0.1)
				(type default)
			)
			(layer "F.Fab")
		)
		(fp_line
			(start -0.12065 0.3048)
			(end -0.67945 0.3048)
			(stroke
				(width 0.1)
				(type default)
			)
			(layer "F.Fab")
		)
		(fp_line
			(start -0.12065 0.2794)
			(end -0.12065 0.3048)
			(stroke
				(width 0.1)
				(type default)
			)
			(layer "F.Fab")
		)
		(fp_line
			(start -0.12065 -0.2794)
			(end 0.12065 -0.2794)
			(stroke
				(width 0.1)
				(type default)
			)
			(layer "F.Fab")
		)
		(fp_line
			(start -0.12065 -0.305054)
			(end -0.12065 -0.2794)
			(stroke
				(width 0.1)
				(type default)
			)
			(layer "F.Fab")
		)
		(fp_line
			(start -0.67945 0.3048)
			(end -0.67945 -0.305054)
			(stroke
				(width 0.1)
				(type default)
			)
			(layer "F.Fab")
		)
		(fp_line
			(start -0.67945 -0.305054)
			(end -0.12065 -0.305054)
			(stroke
				(width 0.1)
				(type default)
			)
			(layer "F.Fab")
		)
		(pad "1" smd circle
			(at -0.40005 0 180)
			(size 0 0)
			(layers "F.Cu" "F.Mask" "F.Paste")
			(net "P3V3_AUX")
		)
		(pad "2" smd circle
			(at 0.40005 0 180)
			(size 0 0)
			(layers "F.Cu" "F.Mask" "F.Paste")
			(net "SSD_LED_IOEXP_A0")
		)
	)
	(footprint ""
		(layer "F.Cu")
		(at 84.709 -27.04973 180)
		(property "Reference" "C2766"
			(at 0 0 180)
			(layer "F.SilkS")
			(hide yes)
			(effects
				(font
					(size 1.27 1.27)
				)
			)
		)
		(property "Value" ""
			(at 0 0 180)
			(layer "F.Fab")
			(effects
				(font
					(size 1.27 1.27)
				)
			)
		)
		(duplicate_pad_numbers_are_jumpers no)
		(fp_line
			(start 0.7874 0.4064)
			(end -0.7874 0.4064)
			(stroke
				(width 0.1524)
				(type default)
			)
			(layer "F.SilkS")
		)
		(fp_line
			(start 0.7874 -0.4064)
			(end 0.7874 0.4064)
			(stroke
				(width 0.1524)
				(type default)
			)
			(layer "F.SilkS")
		)
		(fp_line
			(start -0.7874 0.4064)
			(end -0.7874 -0.4064)
			(stroke
				(width 0.1524)
				(type default)
			)
			(layer "F.SilkS")
		)
		(fp_line
			(start -0.7874 -0.4064)
			(end 0.7874 -0.4064)
			(stroke
				(width 0.1524)
				(type default)
			)
			(layer "F.SilkS")
		)
		(fp_line
			(start 0.67945 0.3048)
			(end 0.120396 0.3048)
			(stroke
				(width 0.1)
				(type default)
			)
			(layer "F.Fab")
		)
		(fp_line
			(start 0.67945 -0.3048)
			(end 0.67945 0.3048)
			(stroke
				(width 0.1)
				(type default)
			)
			(layer "F.Fab")
		)
		(fp_line
			(start 0.12065 -0.2794)
			(end 0.12065 -0.3048)
			(stroke
				(width 0.1)
				(type default)
			)
			(layer "F.Fab")
		)
		(fp_line
			(start 0.12065 -0.3048)
			(end 0.67945 -0.3048)
			(stroke
				(width 0.1)
				(type default)
			)
			(layer "F.Fab")
		)
		(fp_line
			(start 0.120396 0.3048)
			(end 0.120396 0.2794)
			(stroke
				(width 0.1)
				(type default)
			)
			(layer "F.Fab")
		)
		(fp_line
			(start 0.120396 0.2794)
			(end -0.12065 0.2794)
			(stroke
				(width 0.1)
				(type default)
			)
			(layer "F.Fab")
		)
		(fp_line
			(start -0.12065 0.3048)
			(end -0.67945 0.3048)
			(stroke
				(width 0.1)
				(type default)
			)
			(layer "F.Fab")
		)
		(fp_line
			(start -0.12065 0.2794)
			(end -0.12065 0.3048)
			(stroke
				(width 0.1)
				(type default)
			)
			(layer "F.Fab")
		)
		(fp_line
			(start -0.12065 -0.2794)
			(end 0.12065 -0.2794)
			(stroke
				(width 0.1)
				(type default)
			)
			(layer "F.Fab")
		)
		(fp_line
			(start -0.12065 -0.305054)
			(end -0.12065 -0.2794)
			(stroke
				(width 0.1)
				(type default)
			)
			(layer "F.Fab")
		)
		(fp_line
			(start -0.67945 0.3048)
			(end -0.67945 -0.305054)
			(stroke
				(width 0.1)
				(type default)
			)
			(layer "F.Fab")
		)
		(fp_line
			(start -0.67945 -0.305054)
			(end -0.12065 -0.305054)
			(stroke
				(width 0.1)
				(type default)
			)
			(layer "F.Fab")
		)
		(pad "1" smd circle
			(at -0.40005 0 180)
			(size 0 0)
			(layers "F.Cu" "F.Mask" "F.Paste")
			(net "PRSNT_SSD3_R_N")
		)
		(pad "2" smd circle
			(at 0.40005 0 180)
			(size 0 0)
			(layers "F.Cu" "F.Mask" "F.Paste")
			(net "GND")
		)
	)
	(footprint ""
		(layer "F.Cu")
		(at 265.487658 -291.619432)
		(property "Reference" "C3390"
			(at 0 0 0)
			(layer "F.SilkS")
			(hide yes)
			(effects
				(font
					(size 1.27 1.27)
				)
			)
		)
		(property "Value" ""
			(at 0 0 0)
			(layer "F.Fab")
			(effects
				(font
					(size 1.27 1.27)
				)
			)
		)
		(duplicate_pad_numbers_are_jumpers no)
		(fp_line
			(start -1.2954 -0.5842)
			(end 1.2954 -0.5842)
			(stroke
				(width 0.1524)
				(type default)
			)
			(layer "F.SilkS")
		)
		(fp_line
			(start -1.2954 0.5842)
			(end -1.2954 -0.5842)
			(stroke
				(width 0.1524)
				(type default)
			)
			(layer "F.SilkS")
		)
		(fp_line
			(start 1.2954 -0.5842)
			(end 1.2954 0.5842)
			(stroke
				(width 0.1524)
				(type default)
			)
			(layer "F.SilkS")
		)
		(fp_line
			(start 1.2954 0.5842)
			(end -1.2954 0.5842)
			(stroke
				(width 0.1524)
				(type default)
			)
			(layer "F.SilkS")
		)
		(fp_line
			(start -1.1938 -0.4064)
			(end -0.8636 -0.4064)
			(stroke
				(width 0.1)
				(type default)
			)
			(layer "F.Fab")
		)
		(fp_line
			(start -1.1938 0.4064)
			(end -1.1938 -0.4064)
			(stroke
				(width 0.1)
				(type default)
			)
			(layer "F.Fab")
		)
		(fp_line
			(start -0.8636 -0.4572)
			(end 0.8636 -0.4572)
			(stroke
				(width 0.1)
				(type default)
			)
			(layer "F.Fab")
		)
		(fp_line
			(start -0.8636 -0.4064)
			(end -0.8636 -0.4572)
			(stroke
				(width 0.1)
				(type default)
			)
			(layer "F.Fab")
		)
		(fp_line
			(start -0.8636 0.4064)
			(end -1.1938 0.4064)
			(stroke
				(width 0.1)
				(type default)
			)
			(layer "F.Fab")
		)
		(fp_line
			(start -0.8636 0.4572)
			(end -0.8636 0.4064)
			(stroke
				(width 0.1)
				(type default)
			)
			(layer "F.Fab")
		)
		(fp_line
			(start 0.8636 -0.4572)
			(end 0.8636 -0.4064)
			(stroke
				(width 0.1)
				(type default)
			)
			(layer "F.Fab")
		)
		(fp_line
			(start 0.8636 -0.4064)
			(end 1.1938 -0.4064)
			(stroke
				(width 0.1)
				(type default)
			)
			(layer "F.Fab")
		)
		(fp_line
			(start 0.8636 0.4064)
			(end 0.8636 0.4572)
			(stroke
				(width 0.1)
				(type default)
			)
			(layer "F.Fab")
		)
		(fp_line
			(start 0.8636 0.4572)
			(end -0.8636 0.4572)
			(stroke
				(width 0.1)
				(type default)
			)
			(layer "F.Fab")
		)
		(fp_line
			(start 1.1938 -0.4064)
			(end 1.1938 0.4064)
			(stroke
				(width 0.1)
				(type default)
			)
			(layer "F.Fab")
		)
		(fp_line
			(start 1.1938 0.4064)
			(end 0.8636 0.4064)
			(stroke
				(width 0.1)
				(type default)
			)
			(layer "F.Fab")
		)
		(pad "1" smd rect
			(at -0.7366 0 270)
			(size 0.7112 0.8128)
			(layers "F.Cu" "F.Mask" "F.Paste")
			(net "PCEPLL4_VDDA18_PEX2")
		)
		(pad "2" smd rect
			(at 0.7366 0 270)
			(size 0.7112 0.8128)
			(layers "F.Cu" "F.Mask" "F.Paste")
			(net "GND")
		)
	)
	(footprint ""
		(layer "F.Cu")
		(at 442.02604 -125.530864)
		(property "Reference" "PC473"
			(at 0 0 0)
			(layer "F.SilkS")
			(hide yes)
			(effects
				(font
					(size 1.27 1.27)
				)
			)
		)
		(property "Value" ""
			(at 0 0 0)
			(layer "F.Fab")
			(effects
				(font
					(size 1.27 1.27)
				)
			)
		)
		(duplicate_pad_numbers_are_jumpers no)
		(fp_line
			(start -1.524 -0.762)
			(end 1.524 -0.762)
			(stroke
				(width 0.1524)
				(type default)
			)
			(layer "F.SilkS")
		)
		(fp_line
			(start -1.524 0.762)
			(end -1.524 -0.762)
			(stroke
				(width 0.1524)
				(type default)
			)
			(layer "F.SilkS")
		)
		(fp_line
			(start 1.524 -0.762)
			(end 1.524 0.762)
			(stroke
				(width 0.1524)
				(type default)
			)
			(layer "F.SilkS")
		)
		(fp_line
			(start 1.524 0.762)
			(end -1.524 0.762)
			(stroke
				(width 0.1524)
				(type default)
			)
			(layer "F.SilkS")
		)
		(fp_line
			(start -1.1049 -0.724916)
			(end -1.1049 0.724916)
			(stroke
				(width 0.1)
				(type default)
			)
			(layer "F.Fab")
		)
		(fp_line
			(start -1.1049 0.724916)
			(end 1.1049 0.724916)
			(stroke
				(width 0.1)
				(type default)
			)
			(layer "F.Fab")
		)
		(fp_line
			(start 1.1049 -0.724916)
			(end -1.1049 -0.724916)
			(stroke
				(width 0.1)
				(type default)
			)
			(layer "F.Fab")
		)
		(fp_line
			(start 1.1049 0.724916)
			(end 1.1049 -0.724916)
			(stroke
				(width 0.1)
				(type default)
			)
			(layer "F.Fab")
		)
		(pad "1" smd rect
			(at -0.889 0 180)
			(size 1.016 1.27)
			(layers "F.Cu" "F.Mask" "F.Paste")
			(net "GND")
		)
		(pad "2" smd rect
			(at 0.889 0 180)
			(size 1.016 1.27)
			(layers "F.Cu" "F.Mask" "F.Paste")
			(net "P3V3_AUX")
		)
	)
	(footprint ""
		(layer "F.Cu")
		(at 325.099934 -289.230816 -90)
		(property "Reference" "R3978"
			(at 0 0 270)
			(layer "F.SilkS")
			(hide yes)
			(effects
				(font
					(size 1.27 1.27)
				)
			)
		)
		(property "Value" ""
			(at 0 0 270)
			(layer "F.Fab")
			(effects
				(font
					(size 1.27 1.27)
				)
			)
		)
		(duplicate_pad_numbers_are_jumpers no)
		(fp_line
			(start -0.7874 0.4064)
			(end -0.7874 -0.4064)
			(stroke
				(width 0.1524)
				(type default)
			)
			(layer "F.SilkS")
		)
		(fp_line
			(start 0.7874 0.4064)
			(end -0.7874 0.4064)
			(stroke
				(width 0.1524)
				(type default)
			)
			(layer "F.SilkS")
		)
		(fp_line
			(start -0.7874 -0.4064)
			(end 0.7874 -0.4064)
			(stroke
				(width 0.1524)
				(type default)
			)
			(layer "F.SilkS")
		)
		(fp_line
			(start 0.7874 -0.4064)
			(end 0.7874 0.4064)
			(stroke
				(width 0.1524)
				(type default)
			)
			(layer "F.SilkS")
		)
		(fp_line
			(start -0.67945 0.3048)
			(end -0.67945 -0.305054)
			(stroke
				(width 0.1)
				(type default)
			)
			(layer "F.Fab")
		)
		(fp_line
			(start -0.12065 0.3048)
			(end -0.67945 0.3048)
			(stroke
				(width 0.1)
				(type default)
			)
			(layer "F.Fab")
		)
		(fp_line
			(start 0.120396 0.3048)
			(end 0.120396 0.2794)
			(stroke
				(width 0.1)
				(type default)
			)
			(layer "F.Fab")
		)
		(fp_line
			(start 0.67945 0.3048)
			(end 0.120396 0.3048)
			(stroke
				(width 0.1)
				(type default)
			)
			(layer "F.Fab")
		)
		(fp_line
			(start -0.12065 0.2794)
			(end -0.12065 0.3048)
			(stroke
				(width 0.1)
				(type default)
			)
			(layer "F.Fab")
		)
		(fp_line
			(start 0.120396 0.2794)
			(end -0.12065 0.2794)
			(stroke
				(width 0.1)
				(type default)
			)
			(layer "F.Fab")
		)
		(fp_line
			(start -0.12065 -0.2794)
			(end 0.12065 -0.2794)
			(stroke
				(width 0.1)
				(type default)
			)
			(layer "F.Fab")
		)
		(fp_line
			(start 0.12065 -0.2794)
			(end 0.12065 -0.3048)
			(stroke
				(width 0.1)
				(type default)
			)
			(layer "F.Fab")
		)
		(fp_line
			(start 0.12065 -0.3048)
			(end 0.67945 -0.3048)
			(stroke
				(width 0.1)
				(type default)
			)
			(layer "F.Fab")
		)
		(fp_line
			(start 0.67945 -0.3048)
			(end 0.67945 0.3048)
			(stroke
				(width 0.1)
				(type default)
			)
			(layer "F.Fab")
		)
		(fp_line
			(start -0.67945 -0.305054)
			(end -0.12065 -0.305054)
			(stroke
				(width 0.1)
				(type default)
			)
			(layer "F.Fab")
		)
		(fp_line
			(start -0.12065 -0.305054)
			(end -0.12065 -0.2794)
			(stroke
				(width 0.1)
				(type default)
			)
			(layer "F.Fab")
		)
		(pad "1" smd circle
			(at -0.40005 0 270)
			(size 0 0)
			(layers "F.Cu" "F.Mask" "F.Paste")
			(net "SMB_PEX2_HOST_LS_SCL")
		)
		(pad "2" smd circle
			(at 0.40005 0 270)
			(size 0 0)
			(layers "F.Cu" "F.Mask" "F.Paste")
			(net "P3V3_AUX")
		)
	)
	(footprint ""
		(layer "F.Cu")
		(at 198.76135 -144.396714 180)
		(property "Reference" "C225"
			(at 0 0 180)
			(layer "F.SilkS")
			(hide yes)
			(effects
				(font
					(size 1.27 1.27)
				)
			)
		)
		(property "Value" ""
			(at 0 0 180)
			(layer "F.Fab")
			(effects
				(font
					(size 1.27 1.27)
				)
			)
		)
		(duplicate_pad_numbers_are_jumpers no)
		(fp_line
			(start 0.299974 0.150114)
			(end -0.299974 0.150114)
			(stroke
				(width 0.1)
				(type default)
			)
			(layer "F.Fab")
		)
		(fp_line
			(start 0.299974 -0.150114)
			(end 0.299974 0.150114)
			(stroke
				(width 0.1)
				(type default)
			)
			(layer "F.Fab")
		)
		(fp_line
			(start -0.299974 0.150114)
			(end -0.299974 -0.150114)
			(stroke
				(width 0.1)
				(type default)
			)
			(layer "F.Fab")
		)
		(fp_line
			(start -0.299974 -0.150114)
			(end 0.299974 -0.150114)
			(stroke
				(width 0.1)
				(type default)
			)
			(layer "F.Fab")
		)
		(pad "1" smd rect
			(at -0.2667 0 180)
			(size 0.3048 0.381)
			(layers "F.Cu" "F.Mask" "F.Paste")
			(net "P5E_PEX1_STN0_TX_DN<9>")
		)
		(pad "2" smd rect
			(at 0.2667 0 180)
			(size 0.3048 0.381)
			(layers "F.Cu" "F.Mask" "F.Paste")
			(net "P5E_PEX1_STN0_TX_C_DN<9>")
		)
	)
	(footprint ""
		(layer "F.Cu")
		(at 302.922432 -44.341542 90)
		(property "Reference" "R624"
			(at 0 0 90)
			(layer "F.SilkS")
			(hide yes)
			(effects
				(font
					(size 1.27 1.27)
				)
			)
		)
		(property "Value" ""
			(at 0 0 90)
			(layer "F.Fab")
			(effects
				(font
					(size 1.27 1.27)
				)
			)
		)
		(duplicate_pad_numbers_are_jumpers no)
		(fp_line
			(start 0.7874 -0.4064)
			(end 0.7874 0.4064)
			(stroke
				(width 0.1524)
				(type default)
			)
			(layer "F.SilkS")
		)
		(fp_line
			(start -0.7874 -0.4064)
			(end 0.7874 -0.4064)
			(stroke
				(width 0.1524)
				(type default)
			)
			(layer "F.SilkS")
		)
		(fp_line
			(start 0.7874 0.4064)
			(end -0.7874 0.4064)
			(stroke
				(width 0.1524)
				(type default)
			)
			(layer "F.SilkS")
		)
		(fp_line
			(start -0.7874 0.4064)
			(end -0.7874 -0.4064)
			(stroke
				(width 0.1524)
				(type default)
			)
			(layer "F.SilkS")
		)
		(fp_line
			(start -0.12065 -0.305054)
			(end -0.12065 -0.2794)
			(stroke
				(width 0.1)
				(type default)
			)
			(layer "F.Fab")
		)
		(fp_line
			(start -0.67945 -0.305054)
			(end -0.12065 -0.305054)
			(stroke
				(width 0.1)
				(type default)
			)
			(layer "F.Fab")
		)
		(fp_line
			(start 0.67945 -0.3048)
			(end 0.67945 0.3048)
			(stroke
				(width 0.1)
				(type default)
			)
			(layer "F.Fab")
		)
		(fp_line
			(start 0.12065 -0.3048)
			(end 0.67945 -0.3048)
			(stroke
				(width 0.1)
				(type default)
			)
			(layer "F.Fab")
		)
		(fp_line
			(start 0.12065 -0.2794)
			(end 0.12065 -0.3048)
			(stroke
				(width 0.1)
				(type default)
			)
			(layer "F.Fab")
		)
		(fp_line
			(start -0.12065 -0.2794)
			(end 0.12065 -0.2794)
			(stroke
				(width 0.1)
				(type default)
			)
			(layer "F.Fab")
		)
		(fp_line
			(start 0.120396 0.2794)
			(end -0.12065 0.2794)
			(stroke
				(width 0.1)
				(type default)
			)
			(layer "F.Fab")
		)
		(fp_line
			(start -0.12065 0.2794)
			(end -0.12065 0.3048)
			(stroke
				(width 0.1)
				(type default)
			)
			(layer "F.Fab")
		)
		(fp_line
			(start 0.67945 0.3048)
			(end 0.120396 0.3048)
			(stroke
				(width 0.1)
				(type default)
			)
			(layer "F.Fab")
		)
		(fp_line
			(start 0.120396 0.3048)
			(end 0.120396 0.2794)
			(stroke
				(width 0.1)
				(type default)
			)
			(layer "F.Fab")
		)
		(fp_line
			(start -0.12065 0.3048)
			(end -0.67945 0.3048)
			(stroke
				(width 0.1)
				(type default)
			)
			(layer "F.Fab")
		)
		(fp_line
			(start -0.67945 0.3048)
			(end -0.67945 -0.305054)
			(stroke
				(width 0.1)
				(type default)
			)
			(layer "F.Fab")
		)
		(pad "1" smd circle
			(at -0.40005 0 90)
			(size 0 0)
			(layers "F.Cu" "F.Mask" "F.Paste")
			(net "P12V_SSD10")
		)
		(pad "2" smd circle
			(at 0.40005 0 90)
			(size 0 0)
			(layers "F.Cu" "F.Mask" "F.Paste")
			(net "P12V_SSD10_VIN_N")
		)
	)
)
